(kicad_pcb
	(version 20241229)
	(generator "pcbnew")
	(generator_version "9.0")
	(general
		(thickness 1.258)
		(legacy_teardrops no)
	)
	(paper "A4")
	(title_block
		(date "2024-05-27")
		(rev "1.1.2")
		(comment 9 "footprints 55-60 of 64")
	)
	(layers
		(0 "F.Cu" signal)
		(4 "In1.Cu" power)
		(6 "In2.Cu" power)
		(8 "In3.Cu" signal)
		(10 "In4.Cu" signal)
		(2 "B.Cu" signal)
		(9 "F.Adhes" user "F.Adhesive")
		(11 "B.Adhes" user "B.Adhesive")
		(13 "F.Paste" user)
		(15 "B.Paste" user)
		(5 "F.SilkS" user "F.Silkscreen")
		(7 "B.SilkS" user "B.Silkscreen")
		(1 "F.Mask" user)
		(3 "B.Mask" user)
		(17 "Dwgs.User" user "User.Drawings")
		(19 "Cmts.User" user "User.Comments")
		(21 "Eco1.User" user "User.Eco1")
		(23 "Eco2.User" user "User.Eco2")
		(25 "Edge.Cuts" user)
		(27 "Margin" user)
		(31 "F.CrtYd" user "F.Courtyard")
		(29 "B.CrtYd" user "B.Courtyard")
		(35 "F.Fab" user)
		(33 "B.Fab" user)
	)
	(footprint "antmicro-footprints:R_0402_1005Metric"
		(layer "B.Cu")
		(at 143.2 88.2 -135)
		(descr "Resistor SMD 0402")
		(tags "resistor SMD 0402")
		(property "Reference" "R16"
			(at -1.025305 -1.294005 45)
			(layer "B.SilkS")
			(effects
				(font
					(size 0.7 0.7)
					(thickness 0.15)
				)
				(justify left bottom mirror)
			)
		)
		(property "Value" "R_0R_0402"
			(at 0 -1.399999 45)
			(layer "B.Fab")
			(hide yes)
			(effects
				(font
					(size 0.7 0.7)
					(thickness 0.15)
				)
				(justify left bottom mirror)
			)
		)
		(property "Description" "0R resistor in 0402 package with unspecified tolerance"
			(at 0 0 225)
			(layer "F.Fab")
			(hide yes)
			(effects
				(font
					(size 1.27 1.27)
					(thickness 0.15)
				)
			)
		)
		(property "Author" "Antmicro"
			(at 182.090873 251.824509 0)
			(layer "B.Fab")
			(hide yes)
			(effects
				(font
					(size 1 1)
					(thickness 0.15)
				)
				(justify mirror)
			)
		)
		(property "Current" "1A"
			(at 182.090873 251.824509 0)
			(layer "B.Fab")
			(hide yes)
			(effects
				(font
					(size 1 1)
					(thickness 0.15)
				)
				(justify mirror)
			)
		)
		(property "License" "Apache-2.0"
			(at 182.090873 251.824509 0)
			(layer "B.Fab")
			(hide yes)
			(effects
				(font
					(size 1 1)
					(thickness 0.15)
				)
				(justify mirror)
			)
		)
		(property "MPN" "ERJ2GE0R00X"
			(at 182.090873 251.824509 0)
			(layer "B.Fab")
			(hide yes)
			(effects
				(font
					(size 1 1)
					(thickness 0.15)
				)
				(justify mirror)
			)
		)
		(property "Manufacturer" "Panasonic"
			(at 182.090873 251.824509 0)
			(layer "B.Fab")
			(hide yes)
			(effects
				(font
					(size 1 1)
					(thickness 0.15)
				)
				(justify mirror)
			)
		)
		(property "Tolerance" ""
			(at 182.090873 251.824509 0)
			(layer "B.Fab")
			(hide yes)
			(effects
				(font
					(size 1 1)
					(thickness 0.15)
				)
				(justify mirror)
			)
		)
		(property "Val" "0R"
			(at 182.090873 251.824509 0)
			(layer "B.Fab")
			(hide yes)
			(effects
				(font
					(size 1 1)
					(thickness 0.15)
				)
				(justify mirror)
			)
		)
		(sheetname "DDR5")
		(sheetfile "ddr5.kicad_sch")
		(attr smd)
		(fp_poly
			(pts
				(xy -0.925 0.47) (xy 0.925 0.47) (xy 0.925 -0.47) (xy -0.925 -0.47)
			)
			(stroke
				(width 0.05)
				(type default)
			)
			(fill no)
			(layer "B.CrtYd")
		)
		(fp_poly
			(pts
				(xy -0.5 0.25) (xy 0.5 0.25) (xy 0.5 -0.25) (xy -0.5 -0.25)
			)
			(stroke
				(width 0.15)
				(type solid)
			)
			(fill no)
			(layer "B.Fab")
		)
		(pad "1" smd roundrect
			(at -0.48 0 225)
			(size 0.59 0.64)
			(layers "B.Cu" "B.Mask" "B.Paste")
			(roundrect_rratio 0.25)
			(net 63 "/DDR5/R_MIR")
			(pintype "passive")
		)
		(pad "2" smd roundrect
			(at 0.48 0 225)
			(size 0.59 0.64)
			(layers "B.Cu" "B.Mask" "B.Paste")
			(roundrect_rratio 0.25)
			(net 57 "MIR")
			(pintype "passive")
		)
	)
	(footprint "antmicro-footprints:C_0201"
		(layer "B.Cu")
		(at 155.2 80.425 90)
		(descr "Capacitor SMD 0201")
		(tags "capacitor SMD 0201")
		(property "Reference" "C30"
			(at 3.195 0.39 270)
			(layer "B.SilkS")
			(effects
				(font
					(size 0.7 0.7)
					(thickness 0.15)
				)
				(justify left bottom mirror)
			)
		)
		(property "Value" "C_100n_0201"
			(at 0 -1.4 270)
			(layer "B.Fab")
			(hide yes)
			(effects
				(font
					(size 0.7 0.7)
					(thickness 0.15)
				)
				(justify left bottom mirror)
			)
		)
		(property "Description" "SMD Multilayer Ceramic Capacitor, 0.1 µF, 6.3 V, 0201 [0603 Metric], ± 10%, X6S, CC Series"
			(at 0 0 90)
			(layer "F.Fab")
			(hide yes)
			(effects
				(font
					(size 1.27 1.27)
					(thickness 0.15)
				)
			)
		)
		(property "Author" "Antmicro"
			(at 235.625 -74.775 0)
			(layer "B.Fab")
			(hide yes)
			(effects
				(font
					(size 1 1)
					(thickness 0.15)
				)
				(justify mirror)
			)
		)
		(property "Dielectric" ""
			(at 235.625 -74.775 0)
			(layer "B.Fab")
			(hide yes)
			(effects
				(font
					(size 1 1)
					(thickness 0.15)
				)
				(justify mirror)
			)
		)
		(property "License" "Apache-2.0"
			(at 235.625 -74.775 0)
			(layer "B.Fab")
			(hide yes)
			(effects
				(font
					(size 1 1)
					(thickness 0.15)
				)
				(justify mirror)
			)
		)
		(property "MPN" "CC0201KRX6S5BB104"
			(at 235.625 -74.775 0)
			(layer "B.Fab")
			(hide yes)
			(effects
				(font
					(size 1 1)
					(thickness 0.15)
				)
				(justify mirror)
			)
		)
		(property "Manufacturer" "YAGEO"
			(at 235.625 -74.775 0)
			(layer "B.Fab")
			(hide yes)
			(effects
				(font
					(size 1 1)
					(thickness 0.15)
				)
				(justify mirror)
			)
		)
		(property "Public" "False"
			(at 235.625 -74.775 0)
			(layer "B.Fab")
			(hide yes)
			(effects
				(font
					(size 1 1)
					(thickness 0.15)
				)
				(justify mirror)
			)
		)
		(property "Val" "100n"
			(at 235.625 -74.775 0)
			(layer "B.Fab")
			(hide yes)
			(effects
				(font
					(size 1 1)
					(thickness 0.15)
				)
				(justify mirror)
			)
		)
		(property "Voltage" ""
			(at 235.625 -74.775 0)
			(layer "B.Fab")
			(hide yes)
			(effects
				(font
					(size 1 1)
					(thickness 0.15)
				)
				(justify mirror)
			)
		)
		(sheetname "DDR5")
		(sheetfile "ddr5.kicad_sch")
		(attr smd)
		(fp_rect
			(start -0.7 0.35)
			(end 0.7 -0.35)
			(stroke
				(width 0.05)
				(type default)
			)
			(fill no)
			(layer "B.CrtYd")
		)
		(fp_rect
			(start 0.3 -0.15)
			(end -0.301 0.149)
			(stroke
				(width 0.15)
				(type solid)
			)
			(fill no)
			(layer "B.Fab")
		)
		(pad "" smd roundrect
			(at -0.349 0.002 90)
			(size 0.318 0.36)
			(layers "B.Paste")
			(roundrect_rratio 0.25)
		)
		(pad "" smd roundrect
			(at 0.341 0.002 90)
			(size 0.318 0.36)
			(layers "B.Paste")
			(roundrect_rratio 0.25)
		)
		(pad "1" smd roundrect
			(at -0.321 0.002 90)
			(size 0.46 0.4)
			(layers "B.Cu" "B.Mask")
			(roundrect_rratio 0.25)
			(net 18 "VDD")
			(pintype "passive")
		)
		(pad "2" smd roundrect
			(at 0.32 0.002 90)
			(size 0.46 0.4)
			(layers "B.Cu" "B.Mask")
			(roundrect_rratio 0.25)
			(net 1 "GND")
			(pintype "passive")
		)
	)
	(footprint "antmicro-footprints:C_0201"
		(layer "B.Cu")
		(at 152.8 80.43 90)
		(descr "Capacitor SMD 0201")
		(tags "capacitor SMD 0201")
		(property "Reference" "C32"
			(at 3.21 0.32 270)
			(layer "B.SilkS")
			(effects
				(font
					(size 0.7 0.7)
					(thickness 0.15)
				)
				(justify left bottom mirror)
			)
		)
		(property "Value" "C_100n_0201"
			(at 0 -1.4 270)
			(layer "B.Fab")
			(hide yes)
			(effects
				(font
					(size 0.7 0.7)
					(thickness 0.15)
				)
				(justify left bottom mirror)
			)
		)
		(property "Description" "SMD Multilayer Ceramic Capacitor, 0.1 µF, 6.3 V, 0201 [0603 Metric], ± 10%, X6S, CC Series"
			(at 0 0 90)
			(layer "F.Fab")
			(hide yes)
			(effects
				(font
					(size 1.27 1.27)
					(thickness 0.15)
				)
			)
		)
		(property "Author" "Antmicro"
			(at 233.23 -72.37 0)
			(layer "B.Fab")
			(hide yes)
			(effects
				(font
					(size 1 1)
					(thickness 0.15)
				)
				(justify mirror)
			)
		)
		(property "Dielectric" ""
			(at 233.23 -72.37 0)
			(layer "B.Fab")
			(hide yes)
			(effects
				(font
					(size 1 1)
					(thickness 0.15)
				)
				(justify mirror)
			)
		)
		(property "License" "Apache-2.0"
			(at 233.23 -72.37 0)
			(layer "B.Fab")
			(hide yes)
			(effects
				(font
					(size 1 1)
					(thickness 0.15)
				)
				(justify mirror)
			)
		)
		(property "MPN" "CC0201KRX6S5BB104"
			(at 233.23 -72.37 0)
			(layer "B.Fab")
			(hide yes)
			(effects
				(font
					(size 1 1)
					(thickness 0.15)
				)
				(justify mirror)
			)
		)
		(property "Manufacturer" "YAGEO"
			(at 233.23 -72.37 0)
			(layer "B.Fab")
			(hide yes)
			(effects
				(font
					(size 1 1)
					(thickness 0.15)
				)
				(justify mirror)
			)
		)
		(property "Public" "False"
			(at 233.23 -72.37 0)
			(layer "B.Fab")
			(hide yes)
			(effects
				(font
					(size 1 1)
					(thickness 0.15)
				)
				(justify mirror)
			)
		)
		(property "Val" "100n"
			(at 233.23 -72.37 0)
			(layer "B.Fab")
			(hide yes)
			(effects
				(font
					(size 1 1)
					(thickness 0.15)
				)
				(justify mirror)
			)
		)
		(property "Voltage" ""
			(at 233.23 -72.37 0)
			(layer "B.Fab")
			(hide yes)
			(effects
				(font
					(size 1 1)
					(thickness 0.15)
				)
				(justify mirror)
			)
		)
		(sheetname "DDR5")
		(sheetfile "ddr5.kicad_sch")
		(attr smd)
		(fp_rect
			(start -0.7 0.35)
			(end 0.7 -0.35)
			(stroke
				(width 0.05)
				(type default)
			)
			(fill no)
			(layer "B.CrtYd")
		)
		(fp_rect
			(start 0.3 -0.15)
			(end -0.301 0.149)
			(stroke
				(width 0.15)
				(type solid)
			)
			(fill no)
			(layer "B.Fab")
		)
		(pad "" smd roundrect
			(at -0.349 0.002 90)
			(size 0.318 0.36)
			(layers "B.Paste")
			(roundrect_rratio 0.25)
		)
		(pad "" smd roundrect
			(at 0.341 0.002 90)
			(size 0.318 0.36)
			(layers "B.Paste")
			(roundrect_rratio 0.25)
		)
		(pad "1" smd roundrect
			(at -0.321 0.002 90)
			(size 0.46 0.4)
			(layers "B.Cu" "B.Mask")
			(roundrect_rratio 0.25)
			(net 18 "VDD")
			(pintype "passive")
		)
		(pad "2" smd roundrect
			(at 0.32 0.002 90)
			(size 0.46 0.4)
			(layers "B.Cu" "B.Mask")
			(roundrect_rratio 0.25)
			(net 1 "GND")
			(pintype "passive")
		)
	)
	(footprint "antmicro-footprints:R_0402_1005Metric"
		(layer "B.Cu")
		(at 142.4 87.4 -135)
		(descr "Resistor SMD 0402")
		(tags "resistor SMD 0402")
		(property "Reference" "R15"
			(at -1.067731 0.629325 45)
			(layer "B.SilkS")
			(effects
				(font
					(size 0.7 0.7)
					(thickness 0.15)
				)
				(justify left bottom mirror)
			)
		)
		(property "Value" "R_0R_0402"
			(at 0 -1.399999 45)
			(layer "B.Fab")
			(hide yes)
			(effects
				(font
					(size 0.7 0.7)
					(thickness 0.15)
				)
				(justify left bottom mirror)
			)
		)
		(property "Description" "0R resistor in 0402 package with unspecified tolerance"
			(at 0 0 225)
			(layer "F.Fab")
			(hide yes)
			(effects
				(font
					(size 1.27 1.27)
					(thickness 0.15)
				)
			)
		)
		(property "Author" "Antmicro"
			(at 181.290873 249.893138 0)
			(layer "B.Fab")
			(hide yes)
			(effects
				(font
					(size 1 1)
					(thickness 0.15)
				)
				(justify mirror)
			)
		)
		(property "Current" "1A"
			(at 181.290873 249.893138 0)
			(layer "B.Fab")
			(hide yes)
			(effects
				(font
					(size 1 1)
					(thickness 0.15)
				)
				(justify mirror)
			)
		)
		(property "License" "Apache-2.0"
			(at 181.290873 249.893138 0)
			(layer "B.Fab")
			(hide yes)
			(effects
				(font
					(size 1 1)
					(thickness 0.15)
				)
				(justify mirror)
			)
		)
		(property "MPN" "ERJ2GE0R00X"
			(at 181.290873 249.893138 0)
			(layer "B.Fab")
			(hide yes)
			(effects
				(font
					(size 1 1)
					(thickness 0.15)
				)
				(justify mirror)
			)
		)
		(property "Manufacturer" "Panasonic"
			(at 181.290873 249.893138 0)
			(layer "B.Fab")
			(hide yes)
			(effects
				(font
					(size 1 1)
					(thickness 0.15)
				)
				(justify mirror)
			)
		)
		(property "Tolerance" ""
			(at 181.290873 249.893138 0)
			(layer "B.Fab")
			(hide yes)
			(effects
				(font
					(size 1 1)
					(thickness 0.15)
				)
				(justify mirror)
			)
		)
		(property "Val" "0R"
			(at 181.290873 249.893138 0)
			(layer "B.Fab")
			(hide yes)
			(effects
				(font
					(size 1 1)
					(thickness 0.15)
				)
				(justify mirror)
			)
		)
		(sheetname "DDR5")
		(sheetfile "ddr5.kicad_sch")
		(attr smd)
		(fp_poly
			(pts
				(xy -0.925 0.47) (xy 0.925 0.47) (xy 0.925 -0.47) (xy -0.925 -0.47)
			)
			(stroke
				(width 0.05)
				(type default)
			)
			(fill no)
			(layer "B.CrtYd")
		)
		(fp_poly
			(pts
				(xy -0.5 0.25) (xy 0.5 0.25) (xy 0.5 -0.25) (xy -0.5 -0.25)
			)
			(stroke
				(width 0.15)
				(type solid)
			)
			(fill no)
			(layer "B.Fab")
		)
		(pad "1" smd roundrect
			(at -0.48 0 225)
			(size 0.59 0.64)
			(layers "B.Cu" "B.Mask" "B.Paste")
			(roundrect_rratio 0.25)
			(net 62 "/DDR5/R_CAI")
			(pintype "passive")
		)
		(pad "2" smd roundrect
			(at 0.48 0 225)
			(size 0.59 0.64)
			(layers "B.Cu" "B.Mask" "B.Paste")
			(roundrect_rratio 0.25)
			(net 56 "CAI")
			(pintype "passive")
		)
	)
	(footprint "antmicro-footprints:C_0201"
		(layer "B.Cu")
		(at 150.8 86.86 180)
		(descr "Capacitor SMD 0201")
		(tags "capacitor SMD 0201")
		(property "Reference" "C14"
			(at -1.1 -2.045 0)
			(layer "B.SilkS")
			(effects
				(font
					(size 0.7 0.7)
					(thickness 0.15)
				)
				(justify left bottom mirror)
			)
		)
		(property "Value" "C_100n_0201"
			(at 0 -1.4 0)
			(layer "B.Fab")
			(hide yes)
			(effects
				(font
					(size 0.7 0.7)
					(thickness 0.15)
				)
				(justify left bottom mirror)
			)
		)
		(property "Description" "SMD Multilayer Ceramic Capacitor, 0.1 µF, 6.3 V, 0201 [0603 Metric], ± 10%, X6S, CC Series"
			(at 0 0 180)
			(layer "F.Fab")
			(hide yes)
			(effects
				(font
					(size 1.27 1.27)
					(thickness 0.15)
				)
			)
		)
		(property "Author" "Antmicro"
			(at 301.6 173.72 0)
			(layer "B.Fab")
			(hide yes)
			(effects
				(font
					(size 1 1)
					(thickness 0.15)
				)
				(justify mirror)
			)
		)
		(property "Dielectric" ""
			(at 301.6 173.72 0)
			(layer "B.Fab")
			(hide yes)
			(effects
				(font
					(size 1 1)
					(thickness 0.15)
				)
				(justify mirror)
			)
		)
		(property "License" "Apache-2.0"
			(at 301.6 173.72 0)
			(layer "B.Fab")
			(hide yes)
			(effects
				(font
					(size 1 1)
					(thickness 0.15)
				)
				(justify mirror)
			)
		)
		(property "MPN" "CC0201KRX6S5BB104"
			(at 301.6 173.72 0)
			(layer "B.Fab")
			(hide yes)
			(effects
				(font
					(size 1 1)
					(thickness 0.15)
				)
				(justify mirror)
			)
		)
		(property "Manufacturer" "YAGEO"
			(at 301.6 173.72 0)
			(layer "B.Fab")
			(hide yes)
			(effects
				(font
					(size 1 1)
					(thickness 0.15)
				)
				(justify mirror)
			)
		)
		(property "Public" "False"
			(at 301.6 173.72 0)
			(layer "B.Fab")
			(hide yes)
			(effects
				(font
					(size 1 1)
					(thickness 0.15)
				)
				(justify mirror)
			)
		)
		(property "Val" "100n"
			(at 301.6 173.72 0)
			(layer "B.Fab")
			(hide yes)
			(effects
				(font
					(size 1 1)
					(thickness 0.15)
				)
				(justify mirror)
			)
		)
		(property "Voltage" ""
			(at 301.6 173.72 0)
			(layer "B.Fab")
			(hide yes)
			(effects
				(font
					(size 1 1)
					(thickness 0.15)
				)
				(justify mirror)
			)
		)
		(sheetname "DDR5")
		(sheetfile "ddr5.kicad_sch")
		(attr smd)
		(fp_rect
			(start -0.7 0.35)
			(end 0.7 -0.35)
			(stroke
				(width 0.05)
				(type default)
			)
			(fill no)
			(layer "B.CrtYd")
		)
		(fp_rect
			(start 0.3 -0.15)
			(end -0.301 0.149)
			(stroke
				(width 0.15)
				(type solid)
			)
			(fill no)
			(layer "B.Fab")
		)
		(pad "" smd roundrect
			(at -0.349 0.002 180)
			(size 0.318 0.36)
			(layers "B.Paste")
			(roundrect_rratio 0.25)
		)
		(pad "" smd roundrect
			(at 0.341 0.002 180)
			(size 0.318 0.36)
			(layers "B.Paste")
			(roundrect_rratio 0.25)
		)
		(pad "1" smd roundrect
			(at -0.321 0.002 180)
			(size 0.46 0.4)
			(layers "B.Cu" "B.Mask")
			(roundrect_rratio 0.25)
			(net 2 "VDDQ")
			(pintype "passive")
		)
		(pad "2" smd roundrect
			(at 0.32 0.002 180)
			(size 0.46 0.4)
			(layers "B.Cu" "B.Mask")
			(roundrect_rratio 0.25)
			(net 1 "GND")
			(pintype "passive")
		)
	)
	(footprint "antmicro-footprints:R_0402_1005Metric"
		(layer "B.Cu")
		(at 144.3 86.3 -135)
		(descr "Resistor SMD 0402")
		(tags "resistor SMD 0402")
		(property "Reference" "R4"
			(at -0.707107 0.565685 45)
			(layer "B.SilkS")
			(effects
				(font
					(size 0.7 0.7)
					(thickness 0.15)
				)
				(justify left bottom mirror)
			)
		)
		(property "Value" "R_0R_0402"
			(at 0 -1.399999 45)
			(layer "B.Fab")
			(hide yes)
			(effects
				(font
					(size 0.7 0.7)
					(thickness 0.15)
				)
				(justify left bottom mirror)
			)
		)
		(property "Description" "0R resistor in 0402 package with unspecified tolerance"
			(at 0 0 225)
			(layer "F.Fab")
			(hide yes)
			(effects
				(font
					(size 1.27 1.27)
					(thickness 0.15)
				)
			)
		)
		(property "Author" "Antmicro"
			(at 185.312193 249.358824 0)
			(layer "B.Fab")
			(hide yes)
			(effects
				(font
					(size 1 1)
					(thickness 0.15)
				)
				(justify mirror)
			)
		)
		(property "Current" "1A"
			(at 185.312193 249.358824 0)
			(layer "B.Fab")
			(hide yes)
			(effects
				(font
					(size 1 1)
					(thickness 0.15)
				)
				(justify mirror)
			)
		)
		(property "License" "Apache-2.0"
			(at 185.312193 249.358824 0)
			(layer "B.Fab")
			(hide yes)
			(effects
				(font
					(size 1 1)
					(thickness 0.15)
				)
				(justify mirror)
			)
		)
		(property "MPN" "ERJ2GE0R00X"
			(at 185.312193 249.358824 0)
			(layer "B.Fab")
			(hide yes)
			(effects
				(font
					(size 1 1)
					(thickness 0.15)
				)
				(justify mirror)
			)
		)
		(property "Manufacturer" "Panasonic"
			(at 185.312193 249.358824 0)
			(layer "B.Fab")
			(hide yes)
			(effects
				(font
					(size 1 1)
					(thickness 0.15)
				)
				(justify mirror)
			)
		)
		(property "Tolerance" ""
			(at 185.312193 249.358824 0)
			(layer "B.Fab")
			(hide yes)
			(effects
				(font
					(size 1 1)
					(thickness 0.15)
				)
				(justify mirror)
			)
		)
		(property "Val" "0R"
			(at 185.312193 249.358824 0)
			(layer "B.Fab")
			(hide yes)
			(effects
				(font
					(size 1 1)
					(thickness 0.15)
				)
				(justify mirror)
			)
		)
		(sheetname "DDR5")
		(sheetfile "ddr5.kicad_sch")
		(attr smd)
		(fp_poly
			(pts
				(xy -0.925 0.47) (xy 0.925 0.47) (xy 0.925 -0.47) (xy -0.925 -0.47)
			)
			(stroke
				(width 0.05)
				(type default)
			)
			(fill no)
			(layer "B.CrtYd")
		)
		(fp_poly
			(pts
				(xy -0.5 0.25) (xy 0.5 0.25) (xy 0.5 -0.25) (xy -0.5 -0.25)
			)
			(stroke
				(width 0.15)
				(type solid)
			)
			(fill no)
			(layer "B.Fab")
		)
		(pad "1" smd roundrect
			(at -0.48 0 225)
			(size 0.59 0.64)
			(layers "B.Cu" "B.Mask" "B.Paste")
			(roundrect_rratio 0.25)
			(net 59 "/DDR5/R_ALERT_N")
			(pintype "passive")
		)
		(pad "2" smd roundrect
			(at 0.48 0 225)
			(size 0.59 0.64)
			(layers "B.Cu" "B.Mask" "B.Paste")
			(roundrect_rratio 0.25)
			(net 53 "ALERT_N")
			(pintype "passive")
		)
	)
)
